(kicad_pcb
	(version 20260206)
	(generator "pcbnew")
	(generator_version "10.0")
	(general
		(thickness 1.6)
		(legacy_teardrops no)
	)
	(paper "A4")
	(title_block
		(title "01162023_DA0F0TEBIF0_F0T_Expander_BD_F_brd_V02_OCP.brd")
		(comment 1 "Grand Teton / footprints 5515-5519 of 9728")
	)
	(layers
		(0 "F.Cu" signal "TOP")
		(4 "In1.Cu" signal "GND")
		(6 "In2.Cu" signal "VCC")
		(8 "In3.Cu" signal "VCC1")
		(10 "In4.Cu" signal "GND1")
		(12 "In5.Cu" signal "IN1")
		(14 "In6.Cu" signal "GND2")
		(16 "In7.Cu" signal "IN2")
		(18 "In8.Cu" signal "GND3")
		(20 "In9.Cu" signal "IN3")
		(22 "In10.Cu" signal "GND4")
		(24 "In11.Cu" signal "IN4")
		(26 "In12.Cu" signal "GND5")
		(28 "In13.Cu" signal "IN5")
		(30 "In14.Cu" signal "GND6")
		(32 "In15.Cu" signal "IN6")
		(34 "In16.Cu" signal "GND7")
		(2 "B.Cu" signal "BOTTOM")
		(9 "F.Adhes" user "F.Adhesive")
		(11 "B.Adhes" user "B.Adhesive")
		(13 "F.Paste" user "Package Geometry/Pastemask Top")
		(15 "B.Paste" user "Package Geometry/Pastemask Bottom")
		(5 "F.SilkS" user "Ref Des/Silkscreen Top")
		(7 "B.SilkS" user "Ref Des/Silkscreen Bottom")
		(1 "F.Mask" user "Board Geometry/Soldermask Top")
		(3 "B.Mask" user "Board Geometry/Soldermask Bottom")
		(17 "Dwgs.User" user "User.Drawings")
		(19 "Cmts.User" user "User.Comments")
		(21 "Eco1.User" user "User.Eco1")
		(23 "Eco2.User" user "User.Eco2")
		(25 "Edge.Cuts" user "Board Geometry/Outline")
		(27 "Margin" user)
		(31 "F.CrtYd" user "Package Geometry/Place Bound Top")
		(29 "B.CrtYd" user "Package Geometry/Place Bound Bottom")
		(35 "F.Fab" user "Ref Des/Assembly Top")
		(33 "B.Fab" user "Ref Des/Assembly Bottom")
	)
	(footprint ""
		(layer "F.Cu")
		(at 126.63043 -146.099276 180)
		(property "Reference" "PC625"
			(at 0 0 180)
			(layer "F.SilkS")
			(hide yes)
			(effects
				(font
					(size 1.27 1.27)
				)
			)
		)
		(property "Value" ""
			(at 0 0 180)
			(layer "F.Fab")
			(effects
				(font
					(size 1.27 1.27)
				)
			)
		)
		(duplicate_pad_numbers_are_jumpers no)
		(fp_line
			(start 1.524 0.762)
			(end -1.524 0.762)
			(stroke
				(width 0.1524)
				(type default)
			)
			(layer "F.SilkS")
		)
		(fp_line
			(start 1.524 -0.762)
			(end 1.524 0.762)
			(stroke
				(width 0.1524)
				(type default)
			)
			(layer "F.SilkS")
		)
		(fp_line
			(start -1.524 0.762)
			(end -1.524 -0.762)
			(stroke
				(width 0.1524)
				(type default)
			)
			(layer "F.SilkS")
		)
		(fp_line
			(start -1.524 -0.762)
			(end 1.524 -0.762)
			(stroke
				(width 0.1524)
				(type default)
			)
			(layer "F.SilkS")
		)
		(fp_line
			(start 1.1049 0.724916)
			(end 1.1049 -0.724916)
			(stroke
				(width 0.1)
				(type default)
			)
			(layer "F.Fab")
		)
		(fp_line
			(start 1.1049 -0.724916)
			(end -1.1049 -0.724916)
			(stroke
				(width 0.1)
				(type default)
			)
			(layer "F.Fab")
		)
		(fp_line
			(start -1.1049 0.724916)
			(end 1.1049 0.724916)
			(stroke
				(width 0.1)
				(type default)
			)
			(layer "F.Fab")
		)
		(fp_line
			(start -1.1049 -0.724916)
			(end -1.1049 0.724916)
			(stroke
				(width 0.1)
				(type default)
			)
			(layer "F.Fab")
		)
		(pad "1" smd rect
			(at -0.889 0)
			(size 1.016 1.27)
			(layers "F.Cu" "F.Mask" "F.Paste")
			(net "P12V_NIC2_R")
		)
		(pad "2" smd rect
			(at 0.889 0)
			(size 1.016 1.27)
			(layers "F.Cu" "F.Mask" "F.Paste")
			(net "GND")
		)
	)
	(footprint ""
		(layer "F.Cu")
		(at 255.335024 8.083804)
		(property "Reference" "DE13T_2"
			(at -3.6068 -2.962148 0)
			(unlocked yes)
			(layer "F.SilkS")
			(effects
				(font
					(size 0.7874 0.5842)
					(thickness 0.1524)
				)
				(justify left)
			)
		)
		(property "Value" ""
			(at 0 0 0)
			(layer "F.Fab")
			(effects
				(font
					(size 1.27 1.27)
				)
			)
		)
		(duplicate_pad_numbers_are_jumpers no)
		(fp_line
			(start -1.2192 -2.1082)
			(end 1.2192 -2.1082)
			(stroke
				(width 0.1524)
				(type default)
			)
			(layer "F.SilkS")
		)
		(fp_line
			(start -1.2192 2.1082)
			(end -1.2192 -2.1082)
			(stroke
				(width 0.1524)
				(type default)
			)
			(layer "F.SilkS")
		)
		(fp_line
			(start 1.2192 -2.1082)
			(end 1.2192 2.1082)
			(stroke
				(width 0.1524)
				(type default)
			)
			(layer "F.SilkS")
		)
		(fp_line
			(start 1.2192 2.1082)
			(end -1.2192 2.1082)
			(stroke
				(width 0.1524)
				(type default)
			)
			(layer "F.SilkS")
		)
		(pad "" np_thru_hole circle
			(at -2.8829 -1.27 270)
			(size 1.0414 1.0414)
			(drill 1.0414)
			(layers "*.Cu" "*.Mask")
			(clearance 0.381)
			(thermal_gap 0.381)
		)
		(pad "" np_thru_hole circle
			(at -2.8829 1.27 270)
			(size 1.0414 1.0414)
			(drill 1.0414)
			(layers "*.Cu" "*.Mask")
			(clearance 0.381)
			(thermal_gap 0.381)
		)
		(pad "" np_thru_hole circle
			(at 3.4671 -1.27 270)
			(size 1.0414 1.0414)
			(drill 1.0414)
			(layers "*.Cu" "*.Mask")
			(clearance 0.381)
			(thermal_gap 0.381)
		)
		(pad "" np_thru_hole circle
			(at 3.4671 1.27 270)
			(size 1.0414 1.0414)
			(drill 1.0414)
			(layers "*.Cu" "*.Mask")
			(clearance 0.381)
			(thermal_gap 0.381)
		)
		(pad "1" smd rect
			(at 0.8255 -0.249936 270)
			(size 0.3048 0.508)
			(layers "F.Cu" "F.Mask" "F.Paste")
			(net "85_10INCH_IN1_DN")
		)
		(pad "2" smd rect
			(at 0.8255 0.249936 270)
			(size 0.3048 0.508)
			(layers "F.Cu" "F.Mask" "F.Paste")
			(net "85_10INCH_IN1_DP")
		)
		(pad "3" smd circle
			(at 0 0)
			(size 0 0)
			(layers "F.Cu" "F.Mask" "F.Paste")
			(net "COUPON_GND2")
		)
		(zone
			(layer "F.Cu")
			(hatch none 0.5)
			(connect_pads
				(clearance 0)
			)
			(min_thickness 0.25)
			(keepout
				(tracks not_allowed)
				(vias allowed)
				(pads allowed)
				(copperpour not_allowed)
				(footprints allowed)
			)
			(placement
				(enabled no)
				(sheetname "")
			)
			(fill
				(thermal_gap 0.5)
				(thermal_bridge_width 0.5)
				(island_removal_mode 0)
			)
			(polygon
				(pts
					(xy 256.452624 7.535164) (xy 256.452624 7.630668) (xy 255.855724 7.630668) (xy 255.855724 8.037068)
					(xy 256.452624 8.037068) (xy 256.452624 8.13054) (xy 255.855724 8.13054) (xy 255.855724 8.53694)
					(xy 256.452624 8.53694) (xy 256.452624 8.632444) (xy 255.754124 8.632444) (xy 255.754124 7.535164)
				)
			)
		)
		(zone
			(layers "F.Cu" "B.Cu" "In1.Cu" "In2.Cu" "In3.Cu" "In4.Cu" "In5.Cu" "In6.Cu"
				"In7.Cu" "In8.Cu" "In9.Cu" "In10.Cu" "In11.Cu" "In12.Cu" "In13.Cu" "In14.Cu"
				"In15.Cu" "In16.Cu"
			)
			(hatch none 0.5)
			(connect_pads
				(clearance 0)
			)
			(min_thickness 0.25)
			(keepout
				(tracks not_allowed)
				(vias allowed)
				(pads allowed)
				(copperpour not_allowed)
				(footprints allowed)
			)
			(placement
				(enabled no)
				(sheetname "")
			)
			(fill
				(thermal_gap 0.5)
				(thermal_bridge_width 0.5)
				(island_removal_mode 0)
			)
			(polygon
				(pts
					(arc
						(start 253.379224 6.813804)
						(mid 251.525024 6.813804)
						(end 253.379224 6.813804)
					)
				)
			)
		)
		(zone
			(layers "F.Cu" "B.Cu" "In1.Cu" "In2.Cu" "In3.Cu" "In4.Cu" "In5.Cu" "In6.Cu"
				"In7.Cu" "In8.Cu" "In9.Cu" "In10.Cu" "In11.Cu" "In12.Cu" "In13.Cu" "In14.Cu"
				"In15.Cu" "In16.Cu"
			)
			(hatch none 0.5)
			(connect_pads
				(clearance 0)
			)
			(min_thickness 0.25)
			(keepout
				(tracks not_allowed)
				(vias allowed)
				(pads allowed)
				(copperpour not_allowed)
				(footprints allowed)
			)
			(placement
				(enabled no)
				(sheetname "")
			)
			(fill
				(thermal_gap 0.5)
				(thermal_bridge_width 0.5)
				(island_removal_mode 0)
			)
			(polygon
				(pts
					(arc
						(start 253.379224 9.353804)
						(mid 251.525024 9.353804)
						(end 253.379224 9.353804)
					)
				)
			)
		)
		(zone
			(layers "F.Cu" "B.Cu" "In1.Cu" "In2.Cu" "In3.Cu" "In4.Cu" "In5.Cu" "In6.Cu"
				"In7.Cu" "In8.Cu" "In9.Cu" "In10.Cu" "In11.Cu" "In12.Cu" "In13.Cu" "In14.Cu"
				"In15.Cu" "In16.Cu"
			)
			(hatch none 0.5)
			(connect_pads
				(clearance 0)
			)
			(min_thickness 0.25)
			(keepout
				(tracks not_allowed)
				(vias allowed)
				(pads allowed)
				(copperpour not_allowed)
				(footprints allowed)
			)
			(placement
				(enabled no)
				(sheetname "")
			)
			(fill
				(thermal_gap 0.5)
				(thermal_bridge_width 0.5)
				(island_removal_mode 0)
			)
			(polygon
				(pts
					(arc
						(start 259.729224 6.813804)
						(mid 257.875024 6.813804)
						(end 259.729224 6.813804)
					)
				)
			)
		)
		(zone
			(layers "F.Cu" "B.Cu" "In1.Cu" "In2.Cu" "In3.Cu" "In4.Cu" "In5.Cu" "In6.Cu"
				"In7.Cu" "In8.Cu" "In9.Cu" "In10.Cu" "In11.Cu" "In12.Cu" "In13.Cu" "In14.Cu"
				"In15.Cu" "In16.Cu"
			)
			(hatch none 0.5)
			(connect_pads
				(clearance 0)
			)
			(min_thickness 0.25)
			(keepout
				(tracks not_allowed)
				(vias allowed)
				(pads allowed)
				(copperpour not_allowed)
				(footprints allowed)
			)
			(placement
				(enabled no)
				(sheetname "")
			)
			(fill
				(thermal_gap 0.5)
				(thermal_bridge_width 0.5)
				(island_removal_mode 0)
			)
			(polygon
				(pts
					(arc
						(start 259.729224 9.353804)
						(mid 257.875024 9.353804)
						(end 259.729224 9.353804)
					)
				)
			)
		)
	)
	(footprint ""
		(layer "F.Cu")
		(at 221.251272 -148.038312)
		(property "Reference" "R4203"
			(at 0 0 0)
			(layer "F.SilkS")
			(hide yes)
			(effects
				(font
					(size 1.27 1.27)
				)
			)
		)
		(property "Value" ""
			(at 0 0 0)
			(layer "F.Fab")
			(effects
				(font
					(size 1.27 1.27)
				)
			)
		)
		(duplicate_pad_numbers_are_jumpers no)
		(fp_line
			(start -0.7874 -0.4064)
			(end 0.7874 -0.4064)
			(stroke
				(width 0.1524)
				(type default)
			)
			(layer "F.SilkS")
		)
		(fp_line
			(start -0.7874 0.4064)
			(end -0.7874 -0.4064)
			(stroke
				(width 0.1524)
				(type default)
			)
			(layer "F.SilkS")
		)
		(fp_line
			(start 0.7874 -0.4064)
			(end 0.7874 0.4064)
			(stroke
				(width 0.1524)
				(type default)
			)
			(layer "F.SilkS")
		)
		(fp_line
			(start 0.7874 0.4064)
			(end -0.7874 0.4064)
			(stroke
				(width 0.1524)
				(type default)
			)
			(layer "F.SilkS")
		)
		(fp_line
			(start -0.67945 -0.305054)
			(end -0.12065 -0.305054)
			(stroke
				(width 0.1)
				(type default)
			)
			(layer "F.Fab")
		)
		(fp_line
			(start -0.67945 0.3048)
			(end -0.67945 -0.305054)
			(stroke
				(width 0.1)
				(type default)
			)
			(layer "F.Fab")
		)
		(fp_line
			(start -0.12065 -0.305054)
			(end -0.12065 -0.2794)
			(stroke
				(width 0.1)
				(type default)
			)
			(layer "F.Fab")
		)
		(fp_line
			(start -0.12065 -0.2794)
			(end 0.12065 -0.2794)
			(stroke
				(width 0.1)
				(type default)
			)
			(layer "F.Fab")
		)
		(fp_line
			(start -0.12065 0.2794)
			(end -0.12065 0.3048)
			(stroke
				(width 0.1)
				(type default)
			)
			(layer "F.Fab")
		)
		(fp_line
			(start -0.12065 0.3048)
			(end -0.67945 0.3048)
			(stroke
				(width 0.1)
				(type default)
			)
			(layer "F.Fab")
		)
		(fp_line
			(start 0.120396 0.2794)
			(end -0.12065 0.2794)
			(stroke
				(width 0.1)
				(type default)
			)
			(layer "F.Fab")
		)
		(fp_line
			(start 0.120396 0.3048)
			(end 0.120396 0.2794)
			(stroke
				(width 0.1)
				(type default)
			)
			(layer "F.Fab")
		)
		(fp_line
			(start 0.12065 -0.3048)
			(end 0.67945 -0.3048)
			(stroke
				(width 0.1)
				(type default)
			)
			(layer "F.Fab")
		)
		(fp_line
			(start 0.12065 -0.2794)
			(end 0.12065 -0.3048)
			(stroke
				(width 0.1)
				(type default)
			)
			(layer "F.Fab")
		)
		(fp_line
			(start 0.67945 -0.3048)
			(end 0.67945 0.3048)
			(stroke
				(width 0.1)
				(type default)
			)
			(layer "F.Fab")
		)
		(fp_line
			(start 0.67945 0.3048)
			(end 0.120396 0.3048)
			(stroke
				(width 0.1)
				(type default)
			)
			(layer "F.Fab")
		)
		(pad "1" smd circle
			(at -0.40005 0)
			(size 0 0)
			(layers "F.Cu" "F.Mask" "F.Paste")
			(net "GND")
		)
		(pad "2" smd circle
			(at 0.40005 0)
			(size 0 0)
			(layers "F.Cu" "F.Mask" "F.Paste")
			(net "FM_CK440_PEX_MXCK_25M_100M")
		)
	)
	(footprint ""
		(layer "F.Cu")
		(at 411.047438 -87.440008)
		(property "Reference" "R6267"
			(at 0 0 0)
			(layer "F.SilkS")
			(hide yes)
			(effects
				(font
					(size 1.27 1.27)
				)
			)
		)
		(property "Value" ""
			(at 0 0 0)
			(layer "F.Fab")
			(effects
				(font
					(size 1.27 1.27)
				)
			)
		)
		(duplicate_pad_numbers_are_jumpers no)
		(fp_line
			(start -0.7874 -0.4064)
			(end 0.7874 -0.4064)
			(stroke
				(width 0.1524)
				(type default)
			)
			(layer "F.SilkS")
		)
		(fp_line
			(start -0.7874 0.4064)
			(end -0.7874 -0.4064)
			(stroke
				(width 0.1524)
				(type default)
			)
			(layer "F.SilkS")
		)
		(fp_line
			(start 0.7874 -0.4064)
			(end 0.7874 0.4064)
			(stroke
				(width 0.1524)
				(type default)
			)
			(layer "F.SilkS")
		)
		(fp_line
			(start 0.7874 0.4064)
			(end -0.7874 0.4064)
			(stroke
				(width 0.1524)
				(type default)
			)
			(layer "F.SilkS")
		)
		(fp_line
			(start -0.67945 -0.305054)
			(end -0.12065 -0.305054)
			(stroke
				(width 0.1)
				(type default)
			)
			(layer "F.Fab")
		)
		(fp_line
			(start -0.67945 0.3048)
			(end -0.67945 -0.305054)
			(stroke
				(width 0.1)
				(type default)
			)
			(layer "F.Fab")
		)
		(fp_line
			(start -0.12065 -0.305054)
			(end -0.12065 -0.2794)
			(stroke
				(width 0.1)
				(type default)
			)
			(layer "F.Fab")
		)
		(fp_line
			(start -0.12065 -0.2794)
			(end 0.12065 -0.2794)
			(stroke
				(width 0.1)
				(type default)
			)
			(layer "F.Fab")
		)
		(fp_line
			(start -0.12065 0.2794)
			(end -0.12065 0.3048)
			(stroke
				(width 0.1)
				(type default)
			)
			(layer "F.Fab")
		)
		(fp_line
			(start -0.12065 0.3048)
			(end -0.67945 0.3048)
			(stroke
				(width 0.1)
				(type default)
			)
			(layer "F.Fab")
		)
		(fp_line
			(start 0.120396 0.2794)
			(end -0.12065 0.2794)
			(stroke
				(width 0.1)
				(type default)
			)
			(layer "F.Fab")
		)
		(fp_line
			(start 0.120396 0.3048)
			(end 0.120396 0.2794)
			(stroke
				(width 0.1)
				(type default)
			)
			(layer "F.Fab")
		)
		(fp_line
			(start 0.12065 -0.3048)
			(end 0.67945 -0.3048)
			(stroke
				(width 0.1)
				(type default)
			)
			(layer "F.Fab")
		)
		(fp_line
			(start 0.12065 -0.2794)
			(end 0.12065 -0.3048)
			(stroke
				(width 0.1)
				(type default)
			)
			(layer "F.Fab")
		)
		(fp_line
			(start 0.67945 -0.3048)
			(end 0.67945 0.3048)
			(stroke
				(width 0.1)
				(type default)
			)
			(layer "F.Fab")
		)
		(fp_line
			(start 0.67945 0.3048)
			(end 0.120396 0.3048)
			(stroke
				(width 0.1)
				(type default)
			)
			(layer "F.Fab")
		)
		(pad "1" smd circle
			(at -0.40005 0)
			(size 0 0)
			(layers "F.Cu" "F.Mask" "F.Paste")
			(net "SMB_CLK_ISO_R_SDA")
		)
		(pad "2" smd circle
			(at 0.40005 0)
			(size 0 0)
			(layers "F.Cu" "F.Mask" "F.Paste")
			(net "P3V3")
		)
	)
	(footprint ""
		(layer "F.Cu")
		(at 95.105728 -241.760248 180)
		(property "Reference" "R812"
			(at 0 0 180)
			(layer "F.SilkS")
			(hide yes)
			(effects
				(font
					(size 1.27 1.27)
				)
			)
		)
		(property "Value" ""
			(at 0 0 180)
			(layer "F.Fab")
			(effects
				(font
					(size 1.27 1.27)
				)
			)
		)
		(duplicate_pad_numbers_are_jumpers no)
		(fp_line
			(start 0.7874 0.4064)
			(end -0.7874 0.4064)
			(stroke
				(width 0.1524)
				(type default)
			)
			(layer "F.SilkS")
		)
		(fp_line
			(start 0.7874 -0.4064)
			(end 0.7874 0.4064)
			(stroke
				(width 0.1524)
				(type default)
			)
			(layer "F.SilkS")
		)
		(fp_line
			(start -0.7874 0.4064)
			(end -0.7874 -0.4064)
			(stroke
				(width 0.1524)
				(type default)
			)
			(layer "F.SilkS")
		)
		(fp_line
			(start -0.7874 -0.4064)
			(end 0.7874 -0.4064)
			(stroke
				(width 0.1524)
				(type default)
			)
			(layer "F.SilkS")
		)
		(fp_line
			(start 0.67945 0.3048)
			(end 0.120396 0.3048)
			(stroke
				(width 0.1)
				(type default)
			)
			(layer "F.Fab")
		)
		(fp_line
			(start 0.67945 -0.3048)
			(end 0.67945 0.3048)
			(stroke
				(width 0.1)
				(type default)
			)
			(layer "F.Fab")
		)
		(fp_line
			(start 0.12065 -0.2794)
			(end 0.12065 -0.3048)
			(stroke
				(width 0.1)
				(type default)
			)
			(layer "F.Fab")
		)
		(fp_line
			(start 0.12065 -0.3048)
			(end 0.67945 -0.3048)
			(stroke
				(width 0.1)
				(type default)
			)
			(layer "F.Fab")
		)
		(fp_line
			(start 0.120396 0.3048)
			(end 0.120396 0.2794)
			(stroke
				(width 0.1)
				(type default)
			)
			(layer "F.Fab")
		)
		(fp_line
			(start 0.120396 0.2794)
			(end -0.12065 0.2794)
			(stroke
				(width 0.1)
				(type default)
			)
			(layer "F.Fab")
		)
		(fp_line
			(start -0.12065 0.3048)
			(end -0.67945 0.3048)
			(stroke
				(width 0.1)
				(type default)
			)
			(layer "F.Fab")
		)
		(fp_line
			(start -0.12065 0.2794)
			(end -0.12065 0.3048)
			(stroke
				(width 0.1)
				(type default)
			)
			(layer "F.Fab")
		)
		(fp_line
			(start -0.12065 -0.2794)
			(end 0.12065 -0.2794)
			(stroke
				(width 0.1)
				(type default)
			)
			(layer "F.Fab")
		)
		(fp_line
			(start -0.12065 -0.305054)
			(end -0.12065 -0.2794)
			(stroke
				(width 0.1)
				(type default)
			)
			(layer "F.Fab")
		)
		(fp_line
			(start -0.67945 0.3048)
			(end -0.67945 -0.305054)
			(stroke
				(width 0.1)
				(type default)
			)
			(layer "F.Fab")
		)
		(fp_line
			(start -0.67945 -0.305054)
			(end -0.12065 -0.305054)
			(stroke
				(width 0.1)
				(type default)
			)
			(layer "F.Fab")
		)
		(pad "1" smd circle
			(at -0.40005 0 180)
			(size 0 0)
			(layers "F.Cu" "F.Mask" "F.Paste")
			(net "P3V3_AUX")
		)
		(pad "2" smd circle
			(at 0.40005 0 180)
			(size 0 0)
			(layers "F.Cu" "F.Mask" "F.Paste")
			(net "PEX_ADC_ALERT_N")
		)
	)
)
